FILE_TYPE = CONNECTIVITY;
{Allegro Design Entry HDL 17.4-2019 S026 (4007227) 1/17/2022}
"PAGE_NUMBER" = 320;
0"NC";
1"GPU_3V3IO_RSVD5_FFU";
2"PRSNT_CABLE_GPU_A3_N";
3"GND\g";
4"GND\g";
5"P5E_CPU0_P1_TX_BUF_C_DP<7>";
6"P5E_CPU0_P1_TX_BUF_C_DN<7>";
7"P5E_CPU0_P0_TX_BUF_C_DP<7>";
8"P5E_CPU0_P0_TX_BUF_C_DN<7>";
9"P5E_CPU0_P1_RX_BUF_DP<7>";
10"P5E_CPU0_P1_RX_BUF_DN<7>";
11"P5E_CPU0_P0_RX_BUF_DN<7>";
12"P5E_CPU0_P0_RX_BUF_DP<7>";
13"NC_J108_N2";
14"GPU_3V3IO_RSVD3_FFU";
15"P5E_CPU0_P0_RX_BUF_DN<0>";
16"P5E_CPU0_P1_RX_BUF_DP<0>";
17"P5E_CPU0_P0_TX_BUF_C_DP<1>";
18"P5E_CPU0_P0_RX_BUF_DP<3>";
19"P5E_CPU0_P0_RX_BUF_DP<6>";
20"P5E_CPU0_P0_TX_BUF_C_DP<6>";
21"P5E_CPU0_P1_TX_BUF_C_DP<6>";
22"PRSNT_CABLE_GPU_A2_N";
23"P5E_CPU0_P0_RX_BUF_DN<2>";
24"P5E_CPU0_P0_RX_BUF_DP<2>";
25"NC_J108_N4";
26"P5E_CPU0_P0_RX_BUF_DN<3>";
27"P5E_CPU0_P1_TX_BUF_C_DN<0>";
28"P5E_CPU0_P1_TX_BUF_C_DN<2>";
29"P5E_CPU0_P0_RX_BUF_DP<4>";
30"P5E_CPU0_P0_TX_BUF_C_DN<4>";
31"P5E_CPU0_P1_RX_BUF_DN<4>";
32"P5E_CPU0_P1_TX_BUF_C_DP<4>";
33"P5E_CPU0_P1_RX_BUF_DP<4>";
34"P5E_CPU0_P1_TX_BUF_C_DN<4>";
35"P5E_CPU0_P0_TX_BUF_C_DP<4>";
36"P5E_CPU0_P0_TX_BUF_C_DN<5>";
37"NC_J108_N6";
38"P5E_CPU0_P0_RX_BUF_DN<4>";
39"P5E_CPU0_P0_TX_BUF_C_DN<0>";
40"P5E_CPU0_P0_TX_BUF_C_DP<0>";
41"P5E_CPU0_P1_TX_BUF_C_DP<0>";
42"GPU_FPGA_OVERT_N";
43"P5E_CPU0_P0_RX_BUF_DN<6>";
44"P5E_CPU0_P1_RX_BUF_DN<6>";
45"P5E_CPU0_P1_RX_BUF_DP<6>";
46"P5E_CPU0_P0_TX_BUF_C_DN<6>";
47"P5E_CPU0_P1_TX_BUF_C_DN<6>";
48"P5E_CPU0_P0_RX_BUF_DN<5>";
49"P5E_CPU0_P0_RX_BUF_DP<5>";
50"P5E_CPU0_P1_RX_BUF_DN<5>";
51"P5E_CPU0_P1_RX_BUF_DP<5>";
52"P5E_CPU0_P0_TX_BUF_C_DP<5>";
53"P5E_CPU0_P1_TX_BUF_C_DN<5>";
54"P5E_CPU0_P1_TX_BUF_C_DP<5>";
55"P5E_CPU0_P0_TX_BUF_C_DN<3>";
56"P5E_CPU0_P1_RX_BUF_DN<3>";
57"P5E_CPU0_P1_RX_BUF_DP<3>";
58"P5E_CPU0_P0_TX_BUF_C_DP<3>";
59"P5E_CPU0_P1_TX_BUF_C_DN<3>";
60"P5E_CPU0_P1_TX_BUF_C_DP<3>";
61"P5E_CPU0_P1_RX_BUF_DN<2>";
62"P5E_CPU0_P1_RX_BUF_DP<2>";
63"P5E_CPU0_P0_TX_BUF_C_DN<2>";
64"P5E_CPU0_P0_TX_BUF_C_DP<2>";
65"P5E_CPU0_P1_TX_BUF_C_DP<2>";
66"P5E_CPU0_P0_RX_BUF_DN<1>";
67"P5E_CPU0_P0_RX_BUF_DP<1>";
68"P5E_CPU0_P1_RX_BUF_DN<1>";
69"P5E_CPU0_P1_RX_BUF_DP<1>";
70"P5E_CPU0_P0_TX_BUF_C_DN<1>";
71"P5E_CPU0_P1_TX_BUF_C_DN<1>";
72"P5E_CPU0_P1_TX_BUF_C_DP<1>";
73"P5E_CPU0_P0_RX_BUF_DP<0>";
74"P5E_CPU0_P1_RX_BUF_DN<0>";
%"UNIVERSAL_GND"
"1","(-2050,-1300)","0","pure_quanta_power","I14";
;
CDS_LIB"pure_quanta_power"
HDL_POWER"GND";
"A"3;
%"CONN112_10137002101LF"
"1","(-950,600)","0","pure_quanta","I15";
;
LOCATION"J108"
$SEC"1"
CDS_SEC"1"
MATERIAL"IO"
PART_TYPE"THLF"
VALUE"CONN112_10137002-101LF"
CDS_LMAN_SYM_OUTLINE"-775,1650,775,-1650"
NEEDS_NO_SIZE"TRUE"
CDS_LIB"pure_quanta"
PART_NUMBER"DFHSB2FR012";
"N8"
$PN"N8"2;
"M8"
$PN"M8"3;
"N7"
$PN"N7"3;
"M7"
$PN"M7"21;
"N6"
$PN"N6"37;
"M6"
$PN"M6"3;
"N5"
$PN"N5"3;
"M5"
$PN"M5"32;
"L5"
$PN"L5"34;
"L6"
$PN"L6"54;
"L7"
$PN"L7"47;
"L8"
$PN"L8"5;
"K5"
$PN"K5"3;
"K6"
$PN"K6"53;
"K7"
$PN"K7"3;
"K8"
$PN"K8"6;
"J5"
$PN"J5"35;
"J6"
$PN"J6"3;
"J7"
$PN"J7"20;
"J8"
$PN"J8"3;
"I5"
$PN"I5"30;
"I6"
$PN"I6"52;
"I7"
$PN"I7"46;
"I8"
$PN"I8"7;
"H5"
$PN"H5"3;
"H6"
$PN"H6"36;
"H7"
$PN"H7"3;
"H8"
$PN"H8"8;
"G5"
$PN"G5"33;
"G6"
$PN"G6"3;
"G7"
$PN"G7"45;
"G8"
$PN"G8"3;
"F5"
$PN"F5"31;
"F6"
$PN"F6"51;
"F7"
$PN"F7"44;
"F8"
$PN"F8"9;
"E5"
$PN"E5"3;
"E6"
$PN"E6"50;
"E7"
$PN"E7"3;
"E8"
$PN"E8"10;
"D5"
$PN"D5"29;
"D6"
$PN"D6"3;
"D7"
$PN"D7"19;
"D8"
$PN"D8"3;
"C5"
$PN"C5"38;
"C6"
$PN"C6"49;
"C7"
$PN"C7"43;
"C8"
$PN"C8"12;
"B5"
$PN"B5"3;
"B6"
$PN"B6"48;
"B7"
$PN"B7"3;
"B8"
$PN"B8"11;
"A5"
$PN"A5"1;
"A6"
$PN"A6"3;
"A7"
$PN"A7"42;
"A8"
$PN"A8"3;
%"UNIVERSAL_GND"
"1","(2450,-1400)","0","pure_quanta_power","I51";
;
CDS_LIB"pure_quanta_power"
HDL_POWER"GND";
"A"4;
%"CONN112_10137002101LF"
"2","(3600,550)","0","pure_quanta","I72";
;
LOCATION"J108"
$SEC"2"
CDS_SEC"2"
PART_TYPE"THLF"
MATERIAL"IO"
CDS_LMAN_SYM_OUTLINE"-775,1650,775,-1650"
NEEDS_NO_SIZE"TRUE"
CDS_LIB"pure_quanta"
VALUE"CONN112_10137002-101LF"
PART_NUMBER"DFHSB2FR012";
"N4"
$PN"N4"25;
"M4"
$PN"M4"4;
"N3"
$PN"N3"4;
"M3"
$PN"M3"65;
"N2"
$PN"N2"13;
"M2"
$PN"M2"4;
"N1"
$PN"N1"4;
"M1"
$PN"M1"41;
"L1"
$PN"L1"27;
"L2"
$PN"L2"72;
"L3"
$PN"L3"28;
"L4"
$PN"L4"60;
"K1"
$PN"K1"4;
"K2"
$PN"K2"71;
"K3"
$PN"K3"4;
"K4"
$PN"K4"59;
"J1"
$PN"J1"40;
"J2"
$PN"J2"4;
"J3"
$PN"J3"64;
"J4"
$PN"J4"4;
"I1"
$PN"I1"39;
"I2"
$PN"I2"17;
"I3"
$PN"I3"63;
"I4"
$PN"I4"58;
"H1"
$PN"H1"4;
"H2"
$PN"H2"70;
"H3"
$PN"H3"4;
"H4"
$PN"H4"55;
"G1"
$PN"G1"16;
"G2"
$PN"G2"4;
"G3"
$PN"G3"62;
"G4"
$PN"G4"4;
"F1"
$PN"F1"74;
"F2"
$PN"F2"69;
"F3"
$PN"F3"61;
"F4"
$PN"F4"57;
"E1"
$PN"E1"4;
"E2"
$PN"E2"68;
"E3"
$PN"E3"4;
"E4"
$PN"E4"56;
"D1"
$PN"D1"73;
"D2"
$PN"D2"4;
"D3"
$PN"D3"24;
"D4"
$PN"D4"4;
"C1"
$PN"C1"15;
"C2"
$PN"C2"67;
"C3"
$PN"C3"23;
"C4"
$PN"C4"18;
"B1"
$PN"B1"4;
"B2"
$PN"B2"66;
"B3"
$PN"B3"4;
"B4"
$PN"B4"26;
"A1"
$PN"A1"14;
"A2"
$PN"A2"4;
"A3"
$PN"A3"22;
"A4"
$PN"A4"4;
END.
